(kicad_pcb
	(version 20241229)
	(generator "pcbnew")
	(generator_version "9.0")
	(general
		(thickness 1.59)
		(legacy_teardrops no)
	)
	(paper "A3")
	(title_block
		(title "usb-c-power-adapter")
		(date "2025-06-24")
		(rev "1.1.2")
		(company "Antmicro")
		(comment 9 "footprints 45-48 of 122")
	)
	(layers
		(0 "F.Cu" signal)
		(4 "In1.Cu" signal)
		(6 "In2.Cu" signal)
		(2 "B.Cu" signal)
		(9 "F.Adhes" user "F.Adhesive")
		(11 "B.Adhes" user "B.Adhesive")
		(13 "F.Paste" user)
		(15 "B.Paste" user)
		(5 "F.SilkS" user "F.Silkscreen")
		(7 "B.SilkS" user "B.Silkscreen")
		(1 "F.Mask" user)
		(3 "B.Mask" user)
		(17 "Dwgs.User" user "User.Drawings")
		(19 "Cmts.User" user "User.Comments")
		(21 "Eco1.User" user "User.Eco1")
		(23 "Eco2.User" user "User.Eco2")
		(25 "Edge.Cuts" user)
		(27 "Margin" user)
		(31 "F.CrtYd" user "F.Courtyard")
		(29 "B.CrtYd" user "B.Courtyard")
		(35 "F.Fab" user)
		(33 "B.Fab" user)
	)
	(footprint "antmicro-footprints:LED_0603_1608Metric_G"
		(layer "F.Cu")
		(at 91.876 108.5 90)
		(descr "LED SMD 0603 Green")
		(tags "LED SMD 0603 Green")
		(property "Reference" "D4"
			(at 0.575 -0.775 90)
			(layer "F.SilkS")
			(effects
				(font
					(size 0.7 0.7)
					(thickness 0.15)
				)
				(justify right bottom)
			)
		)
		(property "Value" "LED_G_0603_LG_L29K-G2J1-24-Z"
			(at -0.001 1.599 90)
			(layer "F.Fab")
			(effects
				(font
					(size 0.7 0.7)
					(thickness 0.15)
				)
				(justify left bottom)
			)
		)
		(property "Datasheet" "https://look.ams-osram.com/m/19ee86b3ae0ee95b/original/LG-L29K.pdf"
			(at 0 0 90)
			(layer "F.Fab")
			(hide yes)
			(effects
				(font
					(size 1.27 1.27)
					(thickness 0.15)
				)
			)
		)
		(property "Description" "LED, Green, SMD, 0603, 20 mA, 1.7 V, 570 nm"
			(at 0 0 90)
			(layer "F.Fab")
			(hide yes)
			(effects
				(font
					(size 1.27 1.27)
					(thickness 0.15)
				)
			)
		)
		(property "MPN" "LG L29K-G2J1-24-Z"
			(at 0 0 90)
			(unlocked yes)
			(layer "F.Fab")
			(hide yes)
			(effects
				(font
					(size 1 1)
					(thickness 0.15)
				)
			)
		)
		(property "Manufacturer" "OSRAM"
			(at 0 0 90)
			(unlocked yes)
			(layer "F.Fab")
			(hide yes)
			(effects
				(font
					(size 1 1)
					(thickness 0.15)
				)
			)
		)
		(property "Color" "Green"
			(at 0 0 90)
			(unlocked yes)
			(layer "F.Fab")
			(hide yes)
			(effects
				(font
					(size 1 1)
					(thickness 0.15)
				)
			)
		)
		(property "Author" "Antmicro"
			(at 0 0 90)
			(unlocked yes)
			(layer "F.Fab")
			(hide yes)
			(effects
				(font
					(size 1 1)
					(thickness 0.15)
				)
			)
		)
		(property "License" "Apache-2.0"
			(at 0 0 90)
			(unlocked yes)
			(layer "F.Fab")
			(hide yes)
			(effects
				(font
					(size 1 1)
					(thickness 0.15)
				)
			)
		)
		(sheetname "/DC-DC Converters/")
		(sheetfile "dc-dc_converters.kicad_sch")
		(attr smd)
		(fp_line
			(start 0.22 -0.35)
			(end -0.22 -0.35)
			(stroke
				(width 0.15)
				(type solid)
			)
			(layer "F.SilkS")
		)
		(fp_line
			(start -1.18 -0.319)
			(end -1.18 0.321)
			(stroke
				(width 0.15)
				(type solid)
			)
			(layer "F.SilkS")
		)
		(fp_line
			(start 0.105328 0.001008)
			(end 0.24 0.001)
			(stroke
				(width 0.1)
				(type solid)
			)
			(layer "F.SilkS")
		)
		(fp_line
			(start -0.094672 0.001008)
			(end 0.105328 -0.198992)
			(stroke
				(width 0.1)
				(type solid)
			)
			(layer "F.SilkS")
		)
		(fp_line
			(start -0.094672 0.001008)
			(end -0.24 0.001008)
			(stroke
				(width 0.1)
				(type solid)
			)
			(layer "F.SilkS")
		)
		(fp_line
			(start 0.105328 0.201008)
			(end 0.105328 -0.198992)
			(stroke
				(width 0.1)
				(type solid)
			)
			(layer "F.SilkS")
		)
		(fp_line
			(start 0.105328 0.201008)
			(end -0.094672 0.001008)
			(stroke
				(width 0.1)
				(type solid)
			)
			(layer "F.SilkS")
		)
		(fp_line
			(start -0.094672 0.201008)
			(end -0.094672 -0.198992)
			(stroke
				(width 0.1)
				(type solid)
			)
			(layer "F.SilkS")
		)
		(fp_line
			(start 0.22 0.35)
			(end -0.22 0.35)
			(stroke
				(width 0.15)
				(type solid)
			)
			(layer "F.SilkS")
		)
		(fp_rect
			(start 1.25 0.65)
			(end -1.25 -0.65)
			(stroke
				(width 0.05)
				(type solid)
			)
			(fill no)
			(layer "F.CrtYd")
		)
		(fp_line
			(start 0.201 -0.202)
			(end -0.101 0)
			(stroke
				(width 0.15)
				(type solid)
			)
			(layer "F.Fab")
		)
		(fp_line
			(start -0.199 -0.202)
			(end -0.199 0.1)
			(stroke
				(width 0.15)
				(type solid)
			)
			(layer "F.Fab")
		)
		(fp_line
			(start 0.599 0)
			(end 0.201 0)
			(stroke
				(width 0.15)
				(type solid)
			)
			(layer "F.Fab")
		)
		(fp_line
			(start 0.201 0)
			(end 0.201 -0.202)
			(stroke
				(width 0.15)
				(type solid)
			)
			(layer "F.Fab")
		)
		(fp_line
			(start -0.101 0)
			(end 0.201 0.2)
			(stroke
				(width 0.15)
				(type solid)
			)
			(layer "F.Fab")
		)
		(fp_line
			(start -0.199 0)
			(end -0.597 0)
			(stroke
				(width 0.15)
				(type solid)
			)
			(layer "F.Fab")
		)
		(fp_line
			(start 0.201 0.2)
			(end 0.201 0)
			(stroke
				(width 0.15)
				(type solid)
			)
			(layer "F.Fab")
		)
		(fp_line
			(start -0.199 0.2)
			(end -0.199 0.1)
			(stroke
				(width 0.15)
				(type solid)
			)
			(layer "F.Fab")
		)
		(fp_rect
			(start 0.848 0.4)
			(end -0.85 -0.402)
			(stroke
				(width 0.15)
				(type solid)
			)
			(fill no)
			(layer "F.Fab")
		)
		(pad "1" smd roundrect
			(at -0.7 0 270)
			(size 0.8 1)
			(layers "F.Cu" "F.Mask" "F.Paste")
			(roundrect_rratio 0.2)
			(net 2 "GND")
			(pinfunction "C")
			(pintype "passive")
		)
		(pad "2" smd roundrect
			(at 0.7 0 270)
			(size 0.8 1)
			(layers "F.Cu" "F.Mask" "F.Paste")
			(roundrect_rratio 0.2)
			(net 65 "Net-(D4-A)")
			(pinfunction "A")
			(pintype "passive")
		)
	)
	(footprint "antmicro-footprints:LED_0603_1608Metric_G"
		(layer "F.Cu")
		(at 101.05 74.55 90)
		(descr "LED SMD 0603 Green")
		(tags "LED SMD 0603 Green")
		(property "Reference" "D8"
			(at -4.7 -2.574 0)
			(layer "B.SilkS")
			(effects
				(font
					(size 0.7 0.7)
					(thickness 0.15)
				)
				(justify right bottom mirror)
			)
		)
		(property "Value" "LED_G_0603_LG_L29K-G2J1-24-Z"
			(at -0.001 1.599 90)
			(layer "F.Fab")
			(effects
				(font
					(size 0.7 0.7)
					(thickness 0.15)
				)
				(justify left bottom)
			)
		)
		(property "Datasheet" "https://look.ams-osram.com/m/19ee86b3ae0ee95b/original/LG-L29K.pdf"
			(at 0 0 90)
			(layer "F.Fab")
			(hide yes)
			(effects
				(font
					(size 1.27 1.27)
					(thickness 0.15)
				)
			)
		)
		(property "Description" "LED, Green, SMD, 0603, 20 mA, 1.7 V, 570 nm"
			(at 0 0 90)
			(layer "F.Fab")
			(hide yes)
			(effects
				(font
					(size 1.27 1.27)
					(thickness 0.15)
				)
			)
		)
		(property "MPN" "LG L29K-G2J1-24-Z"
			(at 0 0 90)
			(unlocked yes)
			(layer "F.Fab")
			(hide yes)
			(effects
				(font
					(size 1 1)
					(thickness 0.15)
				)
			)
		)
		(property "Manufacturer" "OSRAM"
			(at 0 0 90)
			(unlocked yes)
			(layer "F.Fab")
			(hide yes)
			(effects
				(font
					(size 1 1)
					(thickness 0.15)
				)
			)
		)
		(property "Color" "Green"
			(at 0 0 90)
			(unlocked yes)
			(layer "F.Fab")
			(hide yes)
			(effects
				(font
					(size 1 1)
					(thickness 0.15)
				)
			)
		)
		(property "Author" "Antmicro"
			(at 0 0 90)
			(unlocked yes)
			(layer "F.Fab")
			(hide yes)
			(effects
				(font
					(size 1 1)
					(thickness 0.15)
				)
			)
		)
		(property "License" "Apache-2.0"
			(at 0 0 90)
			(unlocked yes)
			(layer "F.Fab")
			(hide yes)
			(effects
				(font
					(size 1 1)
					(thickness 0.15)
				)
			)
		)
		(sheetname "/DC-DC Converters/")
		(sheetfile "dc-dc_converters.kicad_sch")
		(attr smd)
		(fp_line
			(start 0.22 -0.35)
			(end -0.22 -0.35)
			(stroke
				(width 0.15)
				(type solid)
			)
			(layer "F.SilkS")
		)
		(fp_line
			(start -1.18 -0.319)
			(end -1.18 0.321)
			(stroke
				(width 0.15)
				(type solid)
			)
			(layer "F.SilkS")
		)
		(fp_line
			(start 0.105328 0.001008)
			(end 0.24 0.001)
			(stroke
				(width 0.1)
				(type solid)
			)
			(layer "F.SilkS")
		)
		(fp_line
			(start -0.094672 0.001008)
			(end 0.105328 -0.198992)
			(stroke
				(width 0.1)
				(type solid)
			)
			(layer "F.SilkS")
		)
		(fp_line
			(start -0.094672 0.001008)
			(end -0.24 0.001008)
			(stroke
				(width 0.1)
				(type solid)
			)
			(layer "F.SilkS")
		)
		(fp_line
			(start 0.105328 0.201008)
			(end 0.105328 -0.198992)
			(stroke
				(width 0.1)
				(type solid)
			)
			(layer "F.SilkS")
		)
		(fp_line
			(start 0.105328 0.201008)
			(end -0.094672 0.001008)
			(stroke
				(width 0.1)
				(type solid)
			)
			(layer "F.SilkS")
		)
		(fp_line
			(start -0.094672 0.201008)
			(end -0.094672 -0.198992)
			(stroke
				(width 0.1)
				(type solid)
			)
			(layer "F.SilkS")
		)
		(fp_line
			(start 0.22 0.35)
			(end -0.22 0.35)
			(stroke
				(width 0.15)
				(type solid)
			)
			(layer "F.SilkS")
		)
		(fp_rect
			(start 1.25 0.65)
			(end -1.25 -0.65)
			(stroke
				(width 0.05)
				(type solid)
			)
			(fill no)
			(layer "F.CrtYd")
		)
		(fp_line
			(start 0.201 -0.202)
			(end -0.101 0)
			(stroke
				(width 0.15)
				(type solid)
			)
			(layer "F.Fab")
		)
		(fp_line
			(start -0.199 -0.202)
			(end -0.199 0.1)
			(stroke
				(width 0.15)
				(type solid)
			)
			(layer "F.Fab")
		)
		(fp_line
			(start 0.599 0)
			(end 0.201 0)
			(stroke
				(width 0.15)
				(type solid)
			)
			(layer "F.Fab")
		)
		(fp_line
			(start 0.201 0)
			(end 0.201 -0.202)
			(stroke
				(width 0.15)
				(type solid)
			)
			(layer "F.Fab")
		)
		(fp_line
			(start -0.101 0)
			(end 0.201 0.2)
			(stroke
				(width 0.15)
				(type solid)
			)
			(layer "F.Fab")
		)
		(fp_line
			(start -0.199 0)
			(end -0.597 0)
			(stroke
				(width 0.15)
				(type solid)
			)
			(layer "F.Fab")
		)
		(fp_line
			(start 0.201 0.2)
			(end 0.201 0)
			(stroke
				(width 0.15)
				(type solid)
			)
			(layer "F.Fab")
		)
		(fp_line
			(start -0.199 0.2)
			(end -0.199 0.1)
			(stroke
				(width 0.15)
				(type solid)
			)
			(layer "F.Fab")
		)
		(fp_rect
			(start 0.848 0.4)
			(end -0.85 -0.402)
			(stroke
				(width 0.15)
				(type solid)
			)
			(fill no)
			(layer "F.Fab")
		)
		(pad "1" smd roundrect
			(at -0.7 0 270)
			(size 0.8 1)
			(layers "F.Cu" "F.Mask" "F.Paste")
			(roundrect_rratio 0.2)
			(net 2 "GND")
			(pinfunction "C")
			(pintype "passive")
		)
		(pad "2" smd roundrect
			(at 0.7 0 270)
			(size 0.8 1)
			(layers "F.Cu" "F.Mask" "F.Paste")
			(roundrect_rratio 0.2)
			(net 68 "Net-(D8-A)")
			(pinfunction "A")
			(pintype "passive")
		)
	)
	(footprint "antmicro-footprints:TP_SMD_0.75mm"
		(layer "F.Cu")
		(at 91.086 80.38)
		(property "Reference" "TP6"
			(at 14.076 -6.117 0)
			(layer "F.SilkS")
			(hide yes)
			(effects
				(font
					(size 0.7 0.7)
					(thickness 0.15)
				)
				(justify left bottom)
			)
		)
		(property "Value" "TP_0.75mm_SMD"
			(at 0 1.2 0)
			(layer "F.Fab")
			(effects
				(font
					(size 0.7 0.7)
					(thickness 0.15)
				)
				(justify left bottom)
			)
		)
		(property "Description" "SMT test point"
			(at 0 0 0)
			(layer "F.Fab")
			(hide yes)
			(effects
				(font
					(size 1.27 1.27)
					(thickness 0.15)
				)
			)
		)
		(property "MPN" ""
			(at 0 0 0)
			(unlocked yes)
			(layer "F.Fab")
			(hide yes)
			(effects
				(font
					(size 1 1)
					(thickness 0.15)
				)
			)
		)
		(property "Manufacturer" ""
			(at 0 0 0)
			(unlocked yes)
			(layer "F.Fab")
			(hide yes)
			(effects
				(font
					(size 1 1)
					(thickness 0.15)
				)
			)
		)
		(property "Author" "Antmicro"
			(at 0 0 0)
			(unlocked yes)
			(layer "F.Fab")
			(hide yes)
			(effects
				(font
					(size 1 1)
					(thickness 0.15)
				)
			)
		)
		(property "License" "Apache-2.0"
			(at 0 0 0)
			(unlocked yes)
			(layer "F.Fab")
			(hide yes)
			(effects
				(font
					(size 1 1)
					(thickness 0.15)
				)
			)
		)
		(sheetname "/DC-DC Converters/")
		(sheetfile "dc-dc_converters.kicad_sch")
		(attr exclude_from_bom)
		(fp_circle
			(center 0 0)
			(end 0.475 0)
			(stroke
				(width 0.05)
				(type default)
			)
			(fill no)
			(layer "F.CrtYd")
		)
		(pad "1" smd circle
			(at 0 0)
			(size 0.75 0.75)
			(layers "F.Cu" "F.Mask")
			(net 1 "+3V3")
			(pinfunction "1")
			(pintype "passive")
		)
	)
	(footprint "antmicro-footprints:C_0805_2012Metric"
		(layer "F.Cu")
		(at 91 84.7 90)
		(descr "Capacitor SMD 0805")
		(tags "capacitor SMD 0805")
		(property "Reference" "C3"
			(at -3.04 -5.854 90)
			(layer "F.SilkS")
			(effects
				(font
					(size 0.7 0.7)
					(thickness 0.15)
				)
				(justify left bottom)
			)
		)
		(property "Value" "C_10u_0805_35V"
			(at -2.055717 1.963152 90)
			(layer "F.Fab")
			(effects
				(font
					(size 0.7 0.7)
					(thickness 0.15)
				)
				(justify left bottom)
			)
		)
		(property "Datasheet" "https://www.murata.com/products/productdetail?partno=GRM21BR6YA106KE43%23"
			(at 0 0 90)
			(layer "F.Fab")
			(hide yes)
			(effects
				(font
					(size 1.27 1.27)
					(thickness 0.15)
				)
			)
		)
		(property "Description" "SMD Multilayer Ceramic Capacitor, 10 µF, 35 V, 0805 [2012 Metric], ± 10%, X5R, GRM Series"
			(at 0 0 90)
			(layer "F.Fab")
			(hide yes)
			(effects
				(font
					(size 1.27 1.27)
					(thickness 0.15)
				)
			)
		)
		(property "MPN" "GRM21BR6YA106KE43L"
			(at 0 0 90)
			(unlocked yes)
			(layer "F.Fab")
			(hide yes)
			(effects
				(font
					(size 1 1)
					(thickness 0.15)
				)
			)
		)
		(property "Manufacturer" "Murata"
			(at 0 0 90)
			(unlocked yes)
			(layer "F.Fab")
			(hide yes)
			(effects
				(font
					(size 1 1)
					(thickness 0.15)
				)
			)
		)
		(property "License" "Apache-2.0"
			(at 0 0 90)
			(unlocked yes)
			(layer "F.Fab")
			(hide yes)
			(effects
				(font
					(size 1 1)
					(thickness 0.15)
				)
			)
		)
		(property "Author" "Antmicro"
			(at 0 0 90)
			(unlocked yes)
			(layer "F.Fab")
			(hide yes)
			(effects
				(font
					(size 1 1)
					(thickness 0.15)
				)
			)
		)
		(property "Val" "10u"
			(at 0 0 90)
			(unlocked yes)
			(layer "F.Fab")
			(hide yes)
			(effects
				(font
					(size 1 1)
					(thickness 0.15)
				)
			)
		)
		(property "Voltage" "35V"
			(at 0 0 90)
			(unlocked yes)
			(layer "F.Fab")
			(hide yes)
			(effects
				(font
					(size 1 1)
					(thickness 0.15)
				)
			)
		)
		(property "Dielectric" ""
			(at 0 0 90)
			(unlocked yes)
			(layer "F.Fab")
			(hide yes)
			(effects
				(font
					(size 1 1)
					(thickness 0.15)
				)
			)
		)
		(property "Public" "False"
			(at 0 0 90)
			(unlocked yes)
			(layer "F.Fab")
			(hide yes)
			(effects
				(font
					(size 1 1)
					(thickness 0.15)
				)
			)
		)
		(sheetname "/DC-DC Converters/")
		(sheetfile "dc-dc_converters.kicad_sch")
		(attr smd)
		(fp_line
			(start -0.3 -0.7)
			(end 0.3 -0.7)
			(stroke
				(width 0.15)
				(type solid)
			)
			(layer "F.SilkS")
		)
		(fp_line
			(start -0.3 0.7)
			(end 0.3 0.7)
			(stroke
				(width 0.15)
				(type solid)
			)
			(layer "F.SilkS")
		)
		(fp_rect
			(start 1.95 -0.9)
			(end -1.95 0.9)
			(stroke
				(width 0.05)
				(type default)
			)
			(fill no)
			(layer "F.CrtYd")
		)
		(fp_rect
			(start -0.95 -0.675)
			(end 0.95 0.675)
			(stroke
				(width 0.15)
				(type solid)
			)
			(fill no)
			(layer "F.Fab")
		)
		(pad "1" smd roundrect
			(at -1.1 0 90)
			(size 1.2 1.3)
			(layers "F.Cu" "F.Mask" "F.Paste")
			(roundrect_rratio 0.25)
			(net 2 "GND")
			(pintype "passive")
		)
		(pad "2" smd roundrect
			(at 1.1 0 90)
			(size 1.2 1.3)
			(layers "F.Cu" "F.Mask" "F.Paste")
			(roundrect_rratio 0.25)
			(net 12 "Net-(U2-V_{CIN})")
			(pintype "passive")
		)
	)
)
